# Barreleye-G2_Tri-mode BPX24-DVT-X01-SKU-BOM-X07-20171222_Final.xls.xlsx — DEPOP_GA (bom)
| FOXCONN TECHNOLOGY GROUP |  |  |  |  |  |  |  |  |  |  |  |  |
| BILL OF MATERIAL |  |  |  |  |  |  |  |  |  |  |  |  |
| REV OF  BOM |  | CUSTOMER | <name> |  | CUSTOMER P/N |  | PRODUCT CODE |  | PWA  REV |  | DATE |  |
| Sourcing (Single/Sole/Multi) | Critical Commodity (Y or N) | Component Class (1, 2, other) | Customer PSL (Y or N) | Item Number | Foxconn P/N | Customer P/N | Part Description | Manufacturer  Full Name | Manufacturer  Part Number | Qty | RoHS Status | Location |
